FILE_TYPE = CONNECTIVITY;
{Allegro Design Entry HDL 16.6-p007 (v16-6-112F) 10/10/2012}
"PAGE_NUMBER" = 187;
0"NC";
1"P3E_OCP_CPU0_PE3_C_TXN<7:0>";
2"P3E_CPU0_PE3_OCP_RXP<7:0>";
3"P3E_CPU0_PE3_OCP_RXN<7:0>";
4"P3E_OCP_CPU0_PE3_C_TXP<7:0>";
5"GND\g";
6"GND\g";
7"GND\g";
8"P3V3_STBY\g";
9"P12V_STBY\g";
10"P3E_CPU0_PE3_OCP_RXP<6>";
11"P3E_CPU0_PE3_OCP_RXN<5>";
12"P3E_CPU0_PE3_OCP_RXP<0>";
13"P3E_CPU0_PE3_OCP_RXN<0>";
14"CLK_100M_MEZZ3_DP";
15"CLK_100M_MEZZ3_DN";
16"RST_PCIE_CPU_DEV1_R_N";
17"RST_PCIE_CPU_DEV2_R_N";
18"RST_PCIE_CPU_DEV3_R_N";
19"P3E_CPU0_PE3_OCP_RXP<1>";
20"P3E_CPU0_PE3_OCP_RXN<1>";
21"P3E_OCP_CPU0_PE3_C_TXN<5>";
22"FM_MEZZB_PRSNT1_N";
23"P3E_OCP_CPU0_PE3_C_TXP<4>";
24"P3E_OCP_CPU0_PE3_C_TXP<7>";
25"P3E_OCP_CPU0_PE3_C_TXP<5>";
26"P3E_CPU0_PE3_OCP_RXP<5>";
27"P3E_CPU0_PE3_OCP_RXN<4>";
28"P3E_CPU0_PE3_OCP_RXP<4>";
29"P3E_OCP_CPU0_PE3_C_TXP<3>";
30"P3E_OCP_CPU0_PE3_C_TXN<3>";
31"P3E_OCP_CPU0_PE3_C_TXP<2>";
32"P3E_OCP_CPU0_PE3_C_TXN<2>";
33"RST_PCIE_CPU_DEV3_N";
34"P3E_CPU0_PE3_OCP_RXN<2>";
35"P3E_CPU0_PE3_OCP_RXP<2>";
36"P3E_OCP_CPU0_PE3_C_TXP<6>";
37"P3E_OCP_CPU0_PE3_C_TXN<6>";
38"P3E_OCP_CPU0_PE3_C_TXN<7>";
39"TP_RSVD_B1";
40"RST_PCIE_CPU_DEV2_N";
41"RST_PCIE_CPU_DEV1_N";
42"P3E_CPU0_PE3_OCP_RXP<3>";
43"P3E_CPU0_PE3_OCP_RXN<3>";
44"P3E_OCP_CPU0_PE3_C_TXN<4>";
45"FM_OCP_MEZZB_PRES_N";
46"CLK_100M_MEZZ4_DN";
47"CLK_100M_MEZZ4_DP";
48"P3E_OCP_CPU0_PE3_C_TXP<0>";
49"P3E_OCP_CPU0_PE3_C_TXN<1>";
50"P3E_OCP_CPU0_PE3_C_TXP<1>";
51"P3E_CPU0_PE3_OCP_RXN<6>";
52"P3E_CPU0_PE3_OCP_RXN<7>";
53"P3E_CPU0_PE3_OCP_RXP<7>";
54"P3E_OCP_CPU0_PE3_C_TXN<0>";
%"TAP"
"1","(1550,3300)","0","mstr_standard","I111";
;
HDL_TAP"TRUE"
BODY_TYPE"PLUMBING"
CDS_LIB"mstr_standard";
"B \NAC \NWC"2;
"S \NAC"
BN"4"28;
%"TAP"
"1","(1750,3350)","0","mstr_standard","I112";
;
HDL_TAP"TRUE"
BODY_TYPE"PLUMBING"
CDS_LIB"mstr_standard";
"B \NAC \NWC"3;
"S \NAC"
BN"4"27;
%"TAP"
"1","(1750,3550)","0","mstr_standard","I113";
;
HDL_TAP"TRUE"
BODY_TYPE"PLUMBING"
CDS_LIB"mstr_standard";
"B \NAC \NWC"3;
"S \NAC"
BN"5"11;
%"TAP"
"1","(1550,3500)","0","mstr_standard","I114";
;
HDL_TAP"TRUE"
BODY_TYPE"PLUMBING"
CDS_LIB"mstr_standard";
"B \NAC \NWC"2;
"S \NAC"
BN"5"26;
%"TAP"
"1","(1550,3700)","0","mstr_standard","I115";
;
HDL_TAP"TRUE"
BODY_TYPE"PLUMBING"
CDS_LIB"mstr_standard";
"B \NAC \NWC"2;
"S \NAC"
BN"6"10;
%"TAP"
"1","(1750,3750)","0","mstr_standard","I116";
;
HDL_TAP"TRUE"
BODY_TYPE"PLUMBING"
CDS_LIB"mstr_standard";
"B \NAC \NWC"3;
"S \NAC"
BN"6"51;
%"SCONN80_E67482007"
"1","(-50,3100)","2","mstr_sconn","I119";
;
CDS_SEC"1"
MATERIAL"CONN"
LOCATION"J8E3"
PART_NUMBER"E67482-007"
GROUP"NO_KR"
ROOM"IO_SLOT"
CDS_LOCATION"J8E3"
SEC"1"
SEC_TYPE"SM"
CDS_LIB"mstr_sconn"
CDS_LMAN_SYM_OUTLINE"-250,1100,250,-1100"
PACK_TYPE"SM";
"IO79"
$PN"79"18;
"IO63"
$PN"63"13;
"IO65"
$PN"65"5;
"IO67"
$PN"67"5;
"IO69"
$PN"69"14;
"IO71"
$PN"71"15;
"IO75"
$PN"75"16;
"IO73"
$PN"73"5;
"IO77"
$PN"77"17;
"IO61"
$PN"61"12;
"IO59"
$PN"59"5;
"IO43"
$PN"43"5;
"IO45"
$PN"45"35;
"IO47"
$PN"47"34;
"IO49"
$PN"49"5;
"IO51"
$PN"51"5;
"IO55"
$PN"55"20;
"IO53"
$PN"53"19;
"IO57"
$PN"57"5;
"IO41"
$PN"41"5;
"IO39"
$PN"39"43;
"IO21"
$PN"21"11;
"IO19"
$PN"19"5;
"IO27"
$PN"27"5;
"IO23"
$PN"23"26;
"IO25"
$PN"25"5;
"IO29"
$PN"29"27;
"IO35"
$PN"35"5;
"IO33"
$PN"33"5;
"IO31"
$PN"31"28;
"IO37"
$PN"37"42;
"IO13"
$PN"13"51;
"IO15"
$PN"15"10;
"IO1"
$PN"1"22;
"IO3"
$PN"3"5;
"IO5"
$PN"5"53;
"IO7"
$PN"7"52;
"IO11"
$PN"11"5;
"IO17"
$PN"17"5;
"IO9"
$PN"9"5;
"IO78"
$PN"78"6;
"IO80"
$PN"80"45;
"IO76"
$PN"76"46;
"IO72"
$PN"72"6;
"IO74"
$PN"74"47;
"IO68"
$PN"68"54;
"IO70"
$PN"70"6;
"IO66"
$PN"66"48;
"IO62"
$PN"62"6;
"IO64"
$PN"64"6;
"IO60"
$PN"60"49;
"IO58"
$PN"58"50;
"IO56"
$PN"56"6;
"IO52"
$PN"52"32;
"IO54"
$PN"54"6;
"IO50"
$PN"50"31;
"IO48"
$PN"48"6;
"IO46"
$PN"46"6;
"IO42"
$PN"42"29;
"IO44"
$PN"44"30;
"IO40"
$PN"40"6;
"IO36"
$PN"36"44;
"IO38"
$PN"38"6;
"IO32"
$PN"32"6;
"IO30"
$PN"30"6;
"IO34"
$PN"34"23;
"IO28"
$PN"28"21;
"IO26"
$PN"26"25;
"IO20"
$PN"20"37;
"IO24"
$PN"24"6;
"IO22"
$PN"22"6;
"IO18"
$PN"18"36;
"IO16"
$PN"16"6;
"IO14"
$PN"14"6;
"IO10"
$PN"10"24;
"IO12"
$PN"12"38;
"IO8"
$PN"8"6;
"IO6"
$PN"6"39;
"IO4"
$PN"4"9;
"IO2"
$PN"2"9;
%"TAP"
"1","(1750,2700)","0","mstr_standard","I140";
;
HDL_TAP"TRUE"
BODY_TYPE"PLUMBING"
CDS_LIB"mstr_standard";
"B \NAC \NWC"3;
"S \NAC"
BN"1"20;
%"TAP"
"1","(1750,2900)","0","mstr_standard","I141";
;
HDL_TAP"TRUE"
BODY_TYPE"PLUMBING"
CDS_LIB"mstr_standard";
"B \NAC \NWC"3;
"S \NAC"
BN"2"34;
%"TAP"
"1","(1550,2950)","0","mstr_standard","I142";
;
HDL_TAP"TRUE"
BODY_TYPE"PLUMBING"
CDS_LIB"mstr_standard";
"B \NAC \NWC"2;
"S \NAC"
BN"2"35;
%"RES"
"1","(2275,2200)","0","mstr_discrete","I145";
;
CDS_SEC"1"
WATTAGE"1/16W"
MATERIAL"CHIP"
PACK_TYPE"0402"
TOLERANCE"1%"
VALUE"200.0"
PART_NUMBER"G21796-004"
LOCATION"R9E10"
ROOM"IO_SLOT"
CDS_LOCATION"R9E10"
SEC"1"
SEC_TYPE"0402"
CDS_LIB"mstr_discrete";
"B"
$PN"2"41;
"A"
$PN"1"16;
%"TAP"
"1","(1550,2750)","0","mstr_standard","I147";
;
HDL_TAP"TRUE"
BODY_TYPE"PLUMBING"
CDS_LIB"mstr_standard";
"B \NAC \NWC"2;
"S \NAC"
BN"1"19;
%"TAP"
"1","(1750,2500)","0","mstr_standard","I148";
;
HDL_TAP"TRUE"
BODY_TYPE"PLUMBING"
CDS_LIB"mstr_standard";
"B \NAC \NWC"3;
"S \NAC"
BN"0"13;
%"TAP"
"1","(1550,2550)","0","mstr_standard","I149";
;
HDL_TAP"TRUE"
BODY_TYPE"PLUMBING"
CDS_LIB"mstr_standard";
"B \NAC \NWC"2;
"S \NAC"
BN"0"12;
%"RES"
"1","(1725,2150)","0","mstr_discrete","I150";
;
CDS_SEC"1"
WATTAGE"1/16W"
MATERIAL"CHIP"
PACK_TYPE"0402"
TOLERANCE"1%"
VALUE"200.0"
PART_NUMBER"G21796-004"
LOCATION"R9E11"
ROOM"IO_SLOT"
CDS_LOCATION"R9E11"
SEC"1"
SEC_TYPE"0402"
CDS_LIB"mstr_discrete";
"B"
$PN"2"40;
"A"
$PN"1"17;
%"RES"
"1","(1275,2100)","0","mstr_discrete","I153";
;
CDS_SEC"1"
MATERIAL"CHIP"
TOLERANCE"1%"
PART_NUMBER"G21796-004"
PACK_TYPE"0402"
WATTAGE"1/16W"
VALUE"200.0"
LOCATION"R9E12"
ROOM"IO_SLOT"
CDS_LOCATION"R9E12"
SEC"1"
SEC_TYPE"0402"
CDS_LIB"mstr_discrete";
"B"
$PN"2"33;
"A"
$PN"1"18;
%"GND"
"1","(625,1900)","0","mstr_symbols","I154";
;
HDL_POWER"GND"
BODY_TYPE"PLUMBING"
SIZE"1B"
CDS_LIB"mstr_symbols"
VOLTAGE"0";
"A\NAC"5;
%"TAP"
"1","(-1675,3050)","2","mstr_standard","I155";
;
HDL_TAP"TRUE"
BODY_TYPE"PLUMBING"
CDS_LIB"mstr_standard";
"B \NAC \NWC"4;
"S \NAC"
BN"3"29;
%"TAP"
"1","(-1675,2650)","2","mstr_standard","I156";
;
HDL_TAP"TRUE"
BODY_TYPE"PLUMBING"
CDS_LIB"mstr_standard";
"B \NAC \NWC"4;
"S \NAC"
BN"1"50;
%"TAP"
"1","(-1675,2850)","2","mstr_standard","I157";
;
HDL_TAP"TRUE"
BODY_TYPE"PLUMBING"
CDS_LIB"mstr_standard";
"B \NAC \NWC"4;
"S \NAC"
BN"2"31;
%"TAP"
"1","(-1675,2450)","2","mstr_standard","I158";
;
HDL_TAP"TRUE"
BODY_TYPE"PLUMBING"
CDS_LIB"mstr_standard";
"B \NAC \NWC"4;
"S \NAC"
BN"0"48;
%"GND"
"1","(-725,1850)","0","mstr_symbols","I162";
;
HDL_POWER"GND"
BODY_TYPE"PLUMBING"
SIZE"1B"
CDS_LIB"mstr_symbols"
VOLTAGE"0";
"A\NAC"6;
%"TAP"
"1","(-1950,2600)","2","mstr_standard","I164";
;
HDL_TAP"TRUE"
BODY_TYPE"PLUMBING"
CDS_LIB"mstr_standard";
"B \NAC \NWC"1;
"S \NAC"
BN"1"49;
%"TAP"
"1","(-1950,2800)","2","mstr_standard","I165";
;
HDL_TAP"TRUE"
BODY_TYPE"PLUMBING"
CDS_LIB"mstr_standard";
"B \NAC \NWC"1;
"S \NAC"
BN"2"32;
%"TAP"
"1","(-1950,3000)","2","mstr_standard","I166";
;
HDL_TAP"TRUE"
BODY_TYPE"PLUMBING"
CDS_LIB"mstr_standard";
"B \NAC \NWC"1;
"S \NAC"
BN"3"30;
%"TAP"
"1","(-1950,2400)","2","mstr_standard","I167";
;
HDL_TAP"TRUE"
BODY_TYPE"PLUMBING"
CDS_LIB"mstr_standard";
"B \NAC \NWC"1;
"S \NAC"
BN"0"54;
%"GND"
"1","(1950,4100)","0","mstr_symbols","I169";
;
VOLTAGE"0"
HDL_POWER"GND"
BODY_TYPE"PLUMBING"
SIZE"1B"
CDS_LIB"mstr_symbols";
"A\NAC"7;
%"P3V3_STBY"
"1","(1950,4900)","0","mstr_symbols","I171";
;
SIZE"1B"
BODY_TYPE"PLUMBING"
HDL_POWER"P3V3_STBY"
VOLTAGE"3.3V"
CDS_LIB"mstr_symbols";
"G\NAC"8;
%"RES"
"2","(1950,4675)","0","mstr_discrete","I174";
;
CDS_SEC"1"
CDS_LOCATION"R2W1"
TOLERANCE"1%"
VALUE"10.0K"
PART_NUMBER"G21796-016"
LOCATION"R2W1"
WATTAGE"1/16W"
PACK_TYPE"0402"
MATERIAL"CHIP"
BOM_COST"PROC_SIDEBAND"
ROOM"CPU0"
CDS_LIB"mstr_discrete"
SEC"1"
SEC_TYPE"0402";
"A"
$PN"1"8;
"B"
$PN"2"22;
%"887R2F-L-GP"
"1","(1950,4325)","0","w_hdl","I175";
;
CDS_SEC"1"
CDS_LOCATION"R2R8"
RATED"1/16W"
TOLERANCE"1%"
ATTRIBUTE"887OHM"
VALUE"887R2F-L-GP"
LOCATION"R2R8"
PACK_SIZE"0402"
CDS_LMAN_SYM_OUTLINE"-50,75,50,-75"
CDS_LIB"w_hdl"
PART_NUMBER"64.88705.6DL"
SEC_TYPE"SMD-RG"
SEC"1"
PACK_TYPE"SMD-RG";
"2"
$PN"2"7;
"1"
$PN"1"22;
%"TAP"
"1","(1550,3950)","0","mstr_standard","I46";
;
HDL_TAP"TRUE"
BODY_TYPE"PLUMBING"
CDS_LIB"mstr_standard";
"B \NAC \NWC"2;
"S \NAC"
BN"7"53;
%"TAP"
"1","(1750,3900)","0","mstr_standard","I47";
;
HDL_TAP"TRUE"
BODY_TYPE"PLUMBING"
CDS_LIB"mstr_standard";
"B \NAC \NWC"3;
"S \NAC"
BN"7"52;
%"TAP"
"1","(1750,3100)","0","mstr_standard","I50";
;
HDL_TAP"TRUE"
BODY_TYPE"PLUMBING"
CDS_LIB"mstr_standard";
"B \NAC \NWC"3;
"S \NAC"
BN"3"43;
%"TAP"
"1","(1550,3150)","0","mstr_standard","I51";
;
HDL_TAP"TRUE"
BODY_TYPE"PLUMBING"
CDS_LIB"mstr_standard";
"B \NAC \NWC"2;
"S \NAC"
BN"3"42;
%"P12V_STBY"
"1","(-1000,4375)","0","mstr_symbols","I70";
;
HDL_POWER"P12V_STBY"
BODY_TYPE"PLUMBING"
CDS_LIB"mstr_symbols"
SIZE"1B"
VOLTAGE"12.0V";
"G\NAC"9;
%"TAP"
"1","(-1675,3850)","2","mstr_standard","I87";
;
HDL_TAP"TRUE"
BODY_TYPE"PLUMBING"
CDS_LIB"mstr_standard";
"B \NAC \NWC"4;
"S \NAC"
BN"7"24;
%"TAP"
"1","(-1675,3650)","2","mstr_standard","I88";
;
HDL_TAP"TRUE"
BODY_TYPE"PLUMBING"
CDS_LIB"mstr_standard";
"B \NAC \NWC"4;
"S \NAC"
BN"6"36;
%"TAP"
"1","(-1675,3450)","2","mstr_standard","I89";
;
HDL_TAP"TRUE"
BODY_TYPE"PLUMBING"
CDS_LIB"mstr_standard";
"B \NAC \NWC"4;
"S \NAC"
BN"5"25;
%"TAP"
"1","(-1675,3250)","2","mstr_standard","I90";
;
HDL_TAP"TRUE"
BODY_TYPE"PLUMBING"
CDS_LIB"mstr_standard";
"B \NAC \NWC"4;
"S \NAC"
BN"4"23;
%"TAP"
"1","(-1950,3800)","2","mstr_standard","I95";
;
HDL_TAP"TRUE"
BODY_TYPE"PLUMBING"
CDS_LIB"mstr_standard";
"B \NAC \NWC"1;
"S \NAC"
BN"7"38;
%"TAP"
"1","(-1950,3600)","2","mstr_standard","I96";
;
HDL_TAP"TRUE"
BODY_TYPE"PLUMBING"
CDS_LIB"mstr_standard";
"B \NAC \NWC"1;
"S \NAC"
BN"6"37;
%"TAP"
"1","(-1950,3400)","2","mstr_standard","I97";
;
HDL_TAP"TRUE"
BODY_TYPE"PLUMBING"
CDS_LIB"mstr_standard";
"B \NAC \NWC"1;
"S \NAC"
BN"5"21;
%"TAP"
"1","(-1950,3200)","2","mstr_standard","I98";
;
HDL_TAP"TRUE"
BODY_TYPE"PLUMBING"
CDS_LIB"mstr_standard";
"B \NAC \NWC"1;
"S \NAC"
BN"4"44;
END.
